FILE_TYPE = MULTI_PHYS_TABLE;

PART 'SCONN21_9193031121LF'

{========================================================================================}
:VALUE                   | PART_TYPE | MATERIAL | PART_NUMBER    = STANDARD        | LIFECYCLE          | PART_NUMBER   | JEDEC_TYPE                   | DESCRIPTION                            | MANUFTR | MANUF_PN        | RD_CMPLS_LVL | CMPLS_LVL | CLASS | DIP_SMD | FROM_PJ    | DATA                    | FP_ECN              | EE_CHECK_LIST | CREATOR | CREATEDAY  | PSL | STATUS | ESD_CDM | ESD_HBM | ESD_MM | MSD | PIN_LENGTH_LONG_PIN | PIN_LENGTH_SHORT_PIN ;
{========================================================================================}
 'SCONN21_91930-31121LF' | 'SMLF'    | 'IO'     | 'DFHS21FS003'(!) = ''               | ''               | 'DFHS21FS003' |'CON_F21S2H2D2S_P1W4-22_LDH'| 'CONN SMD HOUSING 21P 2R FS(P1,H3.28)' | 'APL'   | '91930-31121LF' | 'EP(V1)'     | ''        | 'IO'  | ''      | 'F0T-IVES' | 'APL_91930-31121LF.pdf' | '91930-31121LF.msg' | ''            | ''      | '20220421' | ''  | ''     | ''      | ''      | ''     | ''  | '20 MILS'           | '20 MILS'           
 'SCONN21_91930-31121LF' | 'SMLF'    | 'EMPTY'  | 'DFHS21FS003'(!) = ''               | ''               | 'DFHS21FS003' |'CON_F21S2H2D2S_P1W4-22_LDH'| 'CONN SMD HOUSING 21P 2R FS(P1,H3.28)' | 'APL'   | '91930-31121LF' | 'EP(V1)'     | ''        | 'IO'  | ''      | 'F0T-IVES' | 'APL_91930-31121LF.pdf' | '91930-31121LF.msg' | ''            | ''      | '20220421' | ''  | ''     | ''      | ''      | ''     | ''  | '20 MILS'           | '20 MILS'           

END_PART

END.

